(kicad_pcb
	(version 20260206)
	(generator "pcbnew")
	(generator_version "10.0")
	(general
		(thickness 1.6)
		(legacy_teardrops no)
	)
	(paper "A4")
	(title_block
		(title "01162023_DA0F0TEBIF0_F0T_Expander_BD_F_brd_V02_OCP.brd")
		(comment 1 "Grand Teton / footprints 6088-6094 of 9728")
	)
	(layers
		(0 "F.Cu" signal "TOP")
		(4 "In1.Cu" signal "GND")
		(6 "In2.Cu" signal "VCC")
		(8 "In3.Cu" signal "VCC1")
		(10 "In4.Cu" signal "GND1")
		(12 "In5.Cu" signal "IN1")
		(14 "In6.Cu" signal "GND2")
		(16 "In7.Cu" signal "IN2")
		(18 "In8.Cu" signal "GND3")
		(20 "In9.Cu" signal "IN3")
		(22 "In10.Cu" signal "GND4")
		(24 "In11.Cu" signal "IN4")
		(26 "In12.Cu" signal "GND5")
		(28 "In13.Cu" signal "IN5")
		(30 "In14.Cu" signal "GND6")
		(32 "In15.Cu" signal "IN6")
		(34 "In16.Cu" signal "GND7")
		(2 "B.Cu" signal "BOTTOM")
		(9 "F.Adhes" user "F.Adhesive")
		(11 "B.Adhes" user "B.Adhesive")
		(13 "F.Paste" user "Package Geometry/Pastemask Top")
		(15 "B.Paste" user "Package Geometry/Pastemask Bottom")
		(5 "F.SilkS" user "Ref Des/Silkscreen Top")
		(7 "B.SilkS" user "Ref Des/Silkscreen Bottom")
		(1 "F.Mask" user "Board Geometry/Soldermask Top")
		(3 "B.Mask" user "Board Geometry/Soldermask Bottom")
		(17 "Dwgs.User" user "User.Drawings")
		(19 "Cmts.User" user "User.Comments")
		(21 "Eco1.User" user "User.Eco1")
		(23 "Eco2.User" user "User.Eco2")
		(25 "Edge.Cuts" user "Board Geometry/Outline")
		(27 "Margin" user)
		(31 "F.CrtYd" user "Package Geometry/Place Bound Top")
		(29 "B.CrtYd" user "Package Geometry/Place Bound Bottom")
		(35 "F.Fab" user "Ref Des/Assembly Top")
		(33 "B.Fab" user "Ref Des/Assembly Bottom")
	)
	(footprint ""
		(layer "F.Cu")
		(at 284.443678 -43.85691)
		(property "Reference" "R608"
			(at 0 0 0)
			(layer "F.SilkS")
			(hide yes)
			(effects
				(font
					(size 1.27 1.27)
				)
			)
		)
		(property "Value" ""
			(at 0 0 0)
			(layer "F.Fab")
			(effects
				(font
					(size 1.27 1.27)
				)
			)
		)
		(duplicate_pad_numbers_are_jumpers no)
		(fp_line
			(start -0.7874 -0.4064)
			(end 0.7874 -0.4064)
			(stroke
				(width 0.1524)
				(type default)
			)
			(layer "F.SilkS")
		)
		(fp_line
			(start -0.7874 0.4064)
			(end -0.7874 -0.4064)
			(stroke
				(width 0.1524)
				(type default)
			)
			(layer "F.SilkS")
		)
		(fp_line
			(start 0.7874 -0.4064)
			(end 0.7874 0.4064)
			(stroke
				(width 0.1524)
				(type default)
			)
			(layer "F.SilkS")
		)
		(fp_line
			(start 0.7874 0.4064)
			(end -0.7874 0.4064)
			(stroke
				(width 0.1524)
				(type default)
			)
			(layer "F.SilkS")
		)
		(fp_line
			(start -0.67945 -0.305054)
			(end -0.12065 -0.305054)
			(stroke
				(width 0.1)
				(type default)
			)
			(layer "F.Fab")
		)
		(fp_line
			(start -0.67945 0.3048)
			(end -0.67945 -0.305054)
			(stroke
				(width 0.1)
				(type default)
			)
			(layer "F.Fab")
		)
		(fp_line
			(start -0.12065 -0.305054)
			(end -0.12065 -0.2794)
			(stroke
				(width 0.1)
				(type default)
			)
			(layer "F.Fab")
		)
		(fp_line
			(start -0.12065 -0.2794)
			(end 0.12065 -0.2794)
			(stroke
				(width 0.1)
				(type default)
			)
			(layer "F.Fab")
		)
		(fp_line
			(start -0.12065 0.2794)
			(end -0.12065 0.3048)
			(stroke
				(width 0.1)
				(type default)
			)
			(layer "F.Fab")
		)
		(fp_line
			(start -0.12065 0.3048)
			(end -0.67945 0.3048)
			(stroke
				(width 0.1)
				(type default)
			)
			(layer "F.Fab")
		)
		(fp_line
			(start 0.120396 0.2794)
			(end -0.12065 0.2794)
			(stroke
				(width 0.1)
				(type default)
			)
			(layer "F.Fab")
		)
		(fp_line
			(start 0.120396 0.3048)
			(end 0.120396 0.2794)
			(stroke
				(width 0.1)
				(type default)
			)
			(layer "F.Fab")
		)
		(fp_line
			(start 0.12065 -0.3048)
			(end 0.67945 -0.3048)
			(stroke
				(width 0.1)
				(type default)
			)
			(layer "F.Fab")
		)
		(fp_line
			(start 0.12065 -0.2794)
			(end 0.12065 -0.3048)
			(stroke
				(width 0.1)
				(type default)
			)
			(layer "F.Fab")
		)
		(fp_line
			(start 0.67945 -0.3048)
			(end 0.67945 0.3048)
			(stroke
				(width 0.1)
				(type default)
			)
			(layer "F.Fab")
		)
		(fp_line
			(start 0.67945 0.3048)
			(end 0.120396 0.3048)
			(stroke
				(width 0.1)
				(type default)
			)
			(layer "F.Fab")
		)
		(pad "1" smd circle
			(at -0.40005 0)
			(size 0 0)
			(layers "F.Cu" "F.Mask" "F.Paste")
			(net "SSD9_ADC_A1")
		)
		(pad "2" smd circle
			(at 0.40005 0)
			(size 0 0)
			(layers "F.Cu" "F.Mask" "F.Paste")
			(net "GND")
		)
	)
	(footprint ""
		(layer "F.Cu")
		(at 28.005532 -258.511548 -90)
		(property "Reference" "C3074"
			(at 0 0 270)
			(layer "F.SilkS")
			(hide yes)
			(effects
				(font
					(size 1.27 1.27)
				)
			)
		)
		(property "Value" ""
			(at 0 0 270)
			(layer "F.Fab")
			(effects
				(font
					(size 1.27 1.27)
				)
			)
		)
		(duplicate_pad_numbers_are_jumpers no)
		(fp_line
			(start -1.2954 0.5842)
			(end -1.2954 -0.5842)
			(stroke
				(width 0.1524)
				(type default)
			)
			(layer "F.SilkS")
		)
		(fp_line
			(start 1.2954 0.5842)
			(end -1.2954 0.5842)
			(stroke
				(width 0.1524)
				(type default)
			)
			(layer "F.SilkS")
		)
		(fp_line
			(start -1.2954 -0.5842)
			(end 1.2954 -0.5842)
			(stroke
				(width 0.1524)
				(type default)
			)
			(layer "F.SilkS")
		)
		(fp_line
			(start 1.2954 -0.5842)
			(end 1.2954 0.5842)
			(stroke
				(width 0.1524)
				(type default)
			)
			(layer "F.SilkS")
		)
		(fp_line
			(start -0.8636 0.4572)
			(end -0.8636 0.4064)
			(stroke
				(width 0.1)
				(type default)
			)
			(layer "F.Fab")
		)
		(fp_line
			(start 0.8636 0.4572)
			(end -0.8636 0.4572)
			(stroke
				(width 0.1)
				(type default)
			)
			(layer "F.Fab")
		)
		(fp_line
			(start -1.1938 0.4064)
			(end -1.1938 -0.4064)
			(stroke
				(width 0.1)
				(type default)
			)
			(layer "F.Fab")
		)
		(fp_line
			(start -0.8636 0.4064)
			(end -1.1938 0.4064)
			(stroke
				(width 0.1)
				(type default)
			)
			(layer "F.Fab")
		)
		(fp_line
			(start 0.8636 0.4064)
			(end 0.8636 0.4572)
			(stroke
				(width 0.1)
				(type default)
			)
			(layer "F.Fab")
		)
		(fp_line
			(start 1.1938 0.4064)
			(end 0.8636 0.4064)
			(stroke
				(width 0.1)
				(type default)
			)
			(layer "F.Fab")
		)
		(fp_line
			(start -1.1938 -0.4064)
			(end -0.8636 -0.4064)
			(stroke
				(width 0.1)
				(type default)
			)
			(layer "F.Fab")
		)
		(fp_line
			(start -0.8636 -0.4064)
			(end -0.8636 -0.4572)
			(stroke
				(width 0.1)
				(type default)
			)
			(layer "F.Fab")
		)
		(fp_line
			(start 0.8636 -0.4064)
			(end 1.1938 -0.4064)
			(stroke
				(width 0.1)
				(type default)
			)
			(layer "F.Fab")
		)
		(fp_line
			(start 1.1938 -0.4064)
			(end 1.1938 0.4064)
			(stroke
				(width 0.1)
				(type default)
			)
			(layer "F.Fab")
		)
		(fp_line
			(start -0.8636 -0.4572)
			(end 0.8636 -0.4572)
			(stroke
				(width 0.1)
				(type default)
			)
			(layer "F.Fab")
		)
		(fp_line
			(start 0.8636 -0.4572)
			(end 0.8636 -0.4064)
			(stroke
				(width 0.1)
				(type default)
			)
			(layer "F.Fab")
		)
		(pad "1" smd rect
			(at -0.7366 0 180)
			(size 0.7112 0.8128)
			(layers "F.Cu" "F.Mask" "F.Paste")
			(net "P1V8_VDDA_PEX0_R")
		)
		(pad "2" smd rect
			(at 0.7366 0 180)
			(size 0.7112 0.8128)
			(layers "F.Cu" "F.Mask" "F.Paste")
			(net "GND")
		)
	)
	(footprint ""
		(layer "F.Cu")
		(at 411.97784 -114.267742)
		(property "Reference" "R395"
			(at 0 0 0)
			(layer "F.SilkS")
			(hide yes)
			(effects
				(font
					(size 1.27 1.27)
				)
			)
		)
		(property "Value" ""
			(at 0 0 0)
			(layer "F.Fab")
			(effects
				(font
					(size 1.27 1.27)
				)
			)
		)
		(duplicate_pad_numbers_are_jumpers no)
		(fp_line
			(start -0.7874 -0.4064)
			(end 0.7874 -0.4064)
			(stroke
				(width 0.1524)
				(type default)
			)
			(layer "F.SilkS")
		)
		(fp_line
			(start -0.7874 0.4064)
			(end -0.7874 -0.4064)
			(stroke
				(width 0.1524)
				(type default)
			)
			(layer "F.SilkS")
		)
		(fp_line
			(start 0.7874 -0.4064)
			(end 0.7874 0.4064)
			(stroke
				(width 0.1524)
				(type default)
			)
			(layer "F.SilkS")
		)
		(fp_line
			(start 0.7874 0.4064)
			(end -0.7874 0.4064)
			(stroke
				(width 0.1524)
				(type default)
			)
			(layer "F.SilkS")
		)
		(fp_line
			(start -0.67945 -0.305054)
			(end -0.12065 -0.305054)
			(stroke
				(width 0.1)
				(type default)
			)
			(layer "F.Fab")
		)
		(fp_line
			(start -0.67945 0.3048)
			(end -0.67945 -0.305054)
			(stroke
				(width 0.1)
				(type default)
			)
			(layer "F.Fab")
		)
		(fp_line
			(start -0.12065 -0.305054)
			(end -0.12065 -0.2794)
			(stroke
				(width 0.1)
				(type default)
			)
			(layer "F.Fab")
		)
		(fp_line
			(start -0.12065 -0.2794)
			(end 0.12065 -0.2794)
			(stroke
				(width 0.1)
				(type default)
			)
			(layer "F.Fab")
		)
		(fp_line
			(start -0.12065 0.2794)
			(end -0.12065 0.3048)
			(stroke
				(width 0.1)
				(type default)
			)
			(layer "F.Fab")
		)
		(fp_line
			(start -0.12065 0.3048)
			(end -0.67945 0.3048)
			(stroke
				(width 0.1)
				(type default)
			)
			(layer "F.Fab")
		)
		(fp_line
			(start 0.120396 0.2794)
			(end -0.12065 0.2794)
			(stroke
				(width 0.1)
				(type default)
			)
			(layer "F.Fab")
		)
		(fp_line
			(start 0.120396 0.3048)
			(end 0.120396 0.2794)
			(stroke
				(width 0.1)
				(type default)
			)
			(layer "F.Fab")
		)
		(fp_line
			(start 0.12065 -0.3048)
			(end 0.67945 -0.3048)
			(stroke
				(width 0.1)
				(type default)
			)
			(layer "F.Fab")
		)
		(fp_line
			(start 0.12065 -0.2794)
			(end 0.12065 -0.3048)
			(stroke
				(width 0.1)
				(type default)
			)
			(layer "F.Fab")
		)
		(fp_line
			(start 0.67945 -0.3048)
			(end 0.67945 0.3048)
			(stroke
				(width 0.1)
				(type default)
			)
			(layer "F.Fab")
		)
		(fp_line
			(start 0.67945 0.3048)
			(end 0.120396 0.3048)
			(stroke
				(width 0.1)
				(type default)
			)
			(layer "F.Fab")
		)
		(pad "1" smd circle
			(at -0.40005 0)
			(size 0 0)
			(layers "F.Cu" "F.Mask" "F.Paste")
			(net "RST_SMB_NIC7_MUX_ISO_N")
		)
		(pad "2" smd circle
			(at 0.40005 0)
			(size 0 0)
			(layers "F.Cu" "F.Mask" "F.Paste")
			(net "GND")
		)
	)
	(footprint ""
		(layer "F.Cu")
		(at 221.990158 -78.579472)
		(property "Reference" "R5763"
			(at 0 0 0)
			(layer "F.SilkS")
			(hide yes)
			(effects
				(font
					(size 1.27 1.27)
				)
			)
		)
		(property "Value" ""
			(at 0 0 0)
			(layer "F.Fab")
			(effects
				(font
					(size 1.27 1.27)
				)
			)
		)
		(duplicate_pad_numbers_are_jumpers no)
		(fp_line
			(start -0.7874 -0.4064)
			(end 0.7874 -0.4064)
			(stroke
				(width 0.1524)
				(type default)
			)
			(layer "F.SilkS")
		)
		(fp_line
			(start -0.7874 0.4064)
			(end -0.7874 -0.4064)
			(stroke
				(width 0.1524)
				(type default)
			)
			(layer "F.SilkS")
		)
		(fp_line
			(start 0.7874 -0.4064)
			(end 0.7874 0.4064)
			(stroke
				(width 0.1524)
				(type default)
			)
			(layer "F.SilkS")
		)
		(fp_line
			(start 0.7874 0.4064)
			(end -0.7874 0.4064)
			(stroke
				(width 0.1524)
				(type default)
			)
			(layer "F.SilkS")
		)
		(fp_line
			(start -0.67945 -0.305054)
			(end -0.12065 -0.305054)
			(stroke
				(width 0.1)
				(type default)
			)
			(layer "F.Fab")
		)
		(fp_line
			(start -0.67945 0.3048)
			(end -0.67945 -0.305054)
			(stroke
				(width 0.1)
				(type default)
			)
			(layer "F.Fab")
		)
		(fp_line
			(start -0.12065 -0.305054)
			(end -0.12065 -0.2794)
			(stroke
				(width 0.1)
				(type default)
			)
			(layer "F.Fab")
		)
		(fp_line
			(start -0.12065 -0.2794)
			(end 0.12065 -0.2794)
			(stroke
				(width 0.1)
				(type default)
			)
			(layer "F.Fab")
		)
		(fp_line
			(start -0.12065 0.2794)
			(end -0.12065 0.3048)
			(stroke
				(width 0.1)
				(type default)
			)
			(layer "F.Fab")
		)
		(fp_line
			(start -0.12065 0.3048)
			(end -0.67945 0.3048)
			(stroke
				(width 0.1)
				(type default)
			)
			(layer "F.Fab")
		)
		(fp_line
			(start 0.120396 0.2794)
			(end -0.12065 0.2794)
			(stroke
				(width 0.1)
				(type default)
			)
			(layer "F.Fab")
		)
		(fp_line
			(start 0.120396 0.3048)
			(end 0.120396 0.2794)
			(stroke
				(width 0.1)
				(type default)
			)
			(layer "F.Fab")
		)
		(fp_line
			(start 0.12065 -0.3048)
			(end 0.67945 -0.3048)
			(stroke
				(width 0.1)
				(type default)
			)
			(layer "F.Fab")
		)
		(fp_line
			(start 0.12065 -0.2794)
			(end 0.12065 -0.3048)
			(stroke
				(width 0.1)
				(type default)
			)
			(layer "F.Fab")
		)
		(fp_line
			(start 0.67945 -0.3048)
			(end 0.67945 0.3048)
			(stroke
				(width 0.1)
				(type default)
			)
			(layer "F.Fab")
		)
		(fp_line
			(start 0.67945 0.3048)
			(end 0.120396 0.3048)
			(stroke
				(width 0.1)
				(type default)
			)
			(layer "F.Fab")
		)
		(pad "1" smd circle
			(at -0.40005 0)
			(size 0 0)
			(layers "F.Cu" "F.Mask" "F.Paste")
			(net "SSD9_LED")
		)
		(pad "2" smd circle
			(at 0.40005 0)
			(size 0 0)
			(layers "F.Cu" "F.Mask" "F.Paste")
			(net "SSD9_LED_R")
		)
	)
	(footprint ""
		(layer "F.Cu")
		(at 144.595342 -35.48253)
		(property "Reference" "U386"
			(at -2.506472 1.44653 90)
			(unlocked yes)
			(layer "F.SilkS")
			(effects
				(font
					(size 0.7874 0.5842)
					(thickness 0.1524)
				)
				(justify left)
			)
		)
		(property "Value" ""
			(at 0 0 0)
			(layer "F.Fab")
			(effects
				(font
					(size 1.27 1.27)
				)
			)
		)
		(duplicate_pad_numbers_are_jumpers no)
		(fp_line
			(start -1.3462 -1.1938)
			(end -1.3462 1.1684)
			(stroke
				(width 0.1524)
				(type default)
			)
			(layer "F.SilkS")
		)
		(fp_line
			(start -1.3462 1.1938)
			(end 1.3462 1.1938)
			(stroke
				(width 0.1524)
				(type default)
			)
			(layer "F.SilkS")
		)
		(fp_line
			(start 1.3462 -1.1938)
			(end -1.3462 -1.1938)
			(stroke
				(width 0.1524)
				(type default)
			)
			(layer "F.SilkS")
		)
		(fp_line
			(start 1.3462 1.1938)
			(end 1.3462 -1.1938)
			(stroke
				(width 0.1524)
				(type default)
			)
			(layer "F.SilkS")
		)
		(fp_poly
			(pts
				(xy -1.447038 -0.760476) (xy -2.052066 -0.457962) (xy -2.052066 -1.06299)
			)
			(stroke
				(width 0)
				(type default)
			)
			(fill yes)
			(layer "F.SilkS")
		)
		(fp_line
			(start -0.674878 -1.124966)
			(end -0.674878 1.124966)
			(stroke
				(width 0.1)
				(type default)
			)
			(layer "F.Fab")
		)
		(fp_line
			(start -0.674878 1.124966)
			(end 0.674878 1.124966)
			(stroke
				(width 0.1)
				(type default)
			)
			(layer "F.Fab")
		)
		(fp_line
			(start 0.674878 -1.124966)
			(end -0.674878 -1.124966)
			(stroke
				(width 0.1)
				(type default)
			)
			(layer "F.Fab")
		)
		(fp_line
			(start 0.674878 1.124966)
			(end 0.674878 -1.124966)
			(stroke
				(width 0.1)
				(type default)
			)
			(layer "F.Fab")
		)
		(fp_poly
			(pts
				(xy -1.447038 -0.760476) (xy -2.052066 -0.457962) (xy -2.052066 -1.06299)
			)
			(stroke
				(width 0)
				(type default)
			)
			(fill yes)
			(layer "F.Fab")
		)
		(pad "1" smd rect
			(at -0.899922 -0.750062)
			(size 0.6096 0.6096)
			(layers "F.Cu" "F.Mask" "F.Paste")
			(net "PWRGD_P3V3_SSD5_R")
		)
		(pad "2" smd rect
			(at -0.899922 0 90)
			(size 0.4064 0.6096)
			(layers "F.Cu" "F.Mask" "F.Paste")
			(net "RST_SMB_SSD5_N")
		)
		(pad "3" smd rect
			(at -0.899922 0.750062)
			(size 0.6096 0.6096)
			(layers "F.Cu" "F.Mask" "F.Paste")
			(net "GND")
		)
		(pad "4" smd rect
			(at 0.899922 0.750062)
			(size 0.6096 0.6096)
			(layers "F.Cu" "F.Mask" "F.Paste")
			(net "RST_SMB_SSD5_ISO_N")
		)
		(pad "5" smd rect
			(at 0.899922 -0.750062)
			(size 0.6096 0.6096)
			(layers "F.Cu" "F.Mask" "F.Paste")
			(net "P3V3_AUX")
		)
	)
	(footprint ""
		(layer "F.Cu")
		(at 62.963044 -207.3402 180)
		(property "Reference" "R6635"
			(at 0 0 180)
			(layer "F.SilkS")
			(hide yes)
			(effects
				(font
					(size 1.27 1.27)
				)
			)
		)
		(property "Value" ""
			(at 0 0 180)
			(layer "F.Fab")
			(effects
				(font
					(size 1.27 1.27)
				)
			)
		)
		(duplicate_pad_numbers_are_jumpers no)
		(fp_line
			(start 0.7874 0.4064)
			(end -0.7874 0.4064)
			(stroke
				(width 0.1524)
				(type default)
			)
			(layer "F.SilkS")
		)
		(fp_line
			(start 0.7874 -0.4064)
			(end 0.7874 0.4064)
			(stroke
				(width 0.1524)
				(type default)
			)
			(layer "F.SilkS")
		)
		(fp_line
			(start -0.7874 0.4064)
			(end -0.7874 -0.4064)
			(stroke
				(width 0.1524)
				(type default)
			)
			(layer "F.SilkS")
		)
		(fp_line
			(start -0.7874 -0.4064)
			(end 0.7874 -0.4064)
			(stroke
				(width 0.1524)
				(type default)
			)
			(layer "F.SilkS")
		)
		(fp_line
			(start 0.67945 0.3048)
			(end 0.120396 0.3048)
			(stroke
				(width 0.1)
				(type default)
			)
			(layer "F.Fab")
		)
		(fp_line
			(start 0.67945 -0.3048)
			(end 0.67945 0.3048)
			(stroke
				(width 0.1)
				(type default)
			)
			(layer "F.Fab")
		)
		(fp_line
			(start 0.12065 -0.2794)
			(end 0.12065 -0.3048)
			(stroke
				(width 0.1)
				(type default)
			)
			(layer "F.Fab")
		)
		(fp_line
			(start 0.12065 -0.3048)
			(end 0.67945 -0.3048)
			(stroke
				(width 0.1)
				(type default)
			)
			(layer "F.Fab")
		)
		(fp_line
			(start 0.120396 0.3048)
			(end 0.120396 0.2794)
			(stroke
				(width 0.1)
				(type default)
			)
			(layer "F.Fab")
		)
		(fp_line
			(start 0.120396 0.2794)
			(end -0.12065 0.2794)
			(stroke
				(width 0.1)
				(type default)
			)
			(layer "F.Fab")
		)
		(fp_line
			(start -0.12065 0.3048)
			(end -0.67945 0.3048)
			(stroke
				(width 0.1)
				(type default)
			)
			(layer "F.Fab")
		)
		(fp_line
			(start -0.12065 0.2794)
			(end -0.12065 0.3048)
			(stroke
				(width 0.1)
				(type default)
			)
			(layer "F.Fab")
		)
		(fp_line
			(start -0.12065 -0.2794)
			(end 0.12065 -0.2794)
			(stroke
				(width 0.1)
				(type default)
			)
			(layer "F.Fab")
		)
		(fp_line
			(start -0.12065 -0.305054)
			(end -0.12065 -0.2794)
			(stroke
				(width 0.1)
				(type default)
			)
			(layer "F.Fab")
		)
		(fp_line
			(start -0.67945 0.3048)
			(end -0.67945 -0.305054)
			(stroke
				(width 0.1)
				(type default)
			)
			(layer "F.Fab")
		)
		(fp_line
			(start -0.67945 -0.305054)
			(end -0.12065 -0.305054)
			(stroke
				(width 0.1)
				(type default)
			)
			(layer "F.Fab")
		)
		(pad "1" smd circle
			(at -0.40005 0 180)
			(size 0 0)
			(layers "F.Cu" "F.Mask" "F.Paste")
			(net "UART_PEX2_CLI_R_RX")
		)
		(pad "2" smd circle
			(at 0.40005 0 180)
			(size 0 0)
			(layers "F.Cu" "F.Mask" "F.Paste")
			(net "UART_PEX2_CLI_R1_RX")
		)
	)
	(footprint ""
		(layer "F.Cu")
		(at 472.499436 -548.056054 180)
		(property "Reference" "J41_OTH"
			(at -3.2385 -1.402334 0)
			(unlocked yes)
			(layer "B.SilkS")
			(effects
				(font
					(size 0.7874 0.5842)
					(thickness 0.1524)
				)
				(justify mirror)
			)
		)
		(property "Value" ""
			(at 0 0 180)
			(layer "F.Fab")
			(effects
				(font
					(size 1.27 1.27)
				)
			)
		)
		(duplicate_pad_numbers_are_jumpers no)
		(pad "1" thru_hole circle
			(at 0 0 180)
			(size 0.4572 0.4572)
			(drill 0.2032)
			(layers "*.Cu" "*.Mask")
			(remove_unused_layers no)
			(net "Net_9095")
			(clearance 0.127)
			(thermal_gap 0.127)
			(padstack
				(mode front_inner_back)
				(layer "Inner"
					(shape circle)
					(size 0.4572 0.4572)
					(clearance 0.127)
				)
				(layer "B.Cu"
					(shape circle)
					(size 0.508 0.508)
					(clearance 0.1016)
				)
			)
		)
	)
)
